FILE_TYPE = CONNECTIVITY;
{Allegro Design Entry HDL 16.6-p007 (v16-6-112F) 10/10/2012}
"PAGE_NUMBER" = 193;
0"NC";
1"FM_CPU1_VRM_322M_156M_OSC_EN";
2"PVCCMCP_CPU1\g";
3"P1V8_MCP_CPU1\g";
4"PVCCIOMCP_CPU1\g";
5"PVCCIO_CPU1\g";
6"PVCCMCP_CPU1\g";
7"PVCCMCP_CPU1\g";
8"P1V8_MCP_CPU1\g";
9"P1V8_MCP_CPU1\g";
10"PVCCIOMCP_CPU1\g";
11"PVCCIOMCP_CPU1\g";
12"PVCCMCP_CPU1\g"VOLTAGE"1.2V";
13"GND\g";
14"P3V3\g";
15"GND\g";
16"GND\g";
17"GND\g";
18"GND\g";
19"GND\g";
20"GND\g";
21"GND\g";
22"GND\g";
23"P12V_STBY\g";
24"P3V3_STBY\g";
25"P5V_STBY\g";
26"GND\g";
27"GND\g";
28"VR_PVCCIOMCP_CPU1_XADDR1";
29"VR_PVCCMCP_CPU1_XADDR2";
30"SVID_DIO1_CPU1_R";
31"PWRGD_PVCCMCP_CPU1";
32"SVID_CLK1_CPU1_R";
33"SVID_CLK0_CPU1_R";
34"SMB_VR_STBY_LVC3_SCL";
35"SMB_VR_STBY_LVC3_SDA";
36"VSENSE_PVCCIOMCP_CPU1_SKT_VRTN";
37"VSENSE_PVCCIOMCP_CPU1_SKT_VSEN";
38"CLK_322M_156M_CPU1_OSC_VRM_DP";
39"FM_PVCCMCP_CPU1_EN";
40"SVID_DIO0_CPU1_R";
41"SVID_ALERT0_CPU1_R_N";
42"VSENSE_P1V8MCP_CPU1_SKT_VSEN";
43"SVID_ALERT1_CPU1_R_N";
44"FM_P1V8MCP_CPU1_EN";
45"FM_PVCCIOMCP_CPU1_EN";
46"PWRGD_PVCCIOMCP_CPU1";
47"VSENSE_PVCCMCP_CPU1_SKT_VRTN";
48"VSENSE_PVCCMCP_CPU1_SKT_VSEN";
49"VSENSE_P1V8MCP_CPU1_SKT_VRTN";
50"CLK_322M_156M_CPU1_OSC_VRM_DN";
51"PWRGD_P1V8MCP_CPU1";
%"VCC_CORE"
"1","(-3800,4700)","0","mstr_symbols","I107";
;
HDL_POWER"PVCCMCP_CPU1"
CDS_LIB"mstr_symbols";
"A"2;
%"VCC_CORE"
"1","(-4050,4650)","0","mstr_symbols","I131";
;
HDL_POWER"P1V8_MCP_CPU1"
CDS_LIB"mstr_symbols"
VOLTAGE"1.8";
"A"3;
%"VCC_CORE"
"1","(-5250,3225)","0","mstr_symbols","I134";
;
HDL_POWER"PVCCIOMCP_CPU1"
CDS_LIB"mstr_symbols"
VOLTAGE"+0.95";
"A"4;
%"CAP_A"
"1","(-1900,2450)","0","dev_discrete","I140";
;
MATERIAL"X5R"
VOLTAGE"4V"
TOLERANCE"20%"
VALUE"47UF"
LOCATION"C3F1"
PART_NUMBER"602433-106"
PACK_TYPE"0603V"
GROUP"PWR_MCP_CAP"
SEC"1"
SEC_TYPE"0603V"
CDS_SEC"1"
CDS_LIB"dev_discrete"
CDS_LOCATION"C3F1";
"B"
$PN"2"19;
"A"
$PN"1"8;
%"CAP_A"
"1","(-1600,2450)","0","dev_discrete","I141";
;
LOCATION"C4F2"
PACK_TYPE"0603V"
PART_NUMBER"602433-106"
MATERIAL"X5R"
TOLERANCE"20%"
VOLTAGE"4V"
VALUE"47UF"
GROUP"PWR_MCP_CAP"
CDS_LOCATION"C4F2"
CDS_LIB"dev_discrete"
CDS_SEC"1"
SEC_TYPE"0603V"
SEC"1";
"B"
$PN"2"19;
"A"
$PN"1"8;
%"PVCCIO_CPU1"
"1","(-7225,4575)","0","mstr_symbols","I144";
;
ROOM"PVCCIO_CPU1"
BOM_COST"PROC_VRD_PVCCIO_CPU1"
CDS_LIB"mstr_symbols"
VOLTAGE"1.1V"
BODY_TYPE"PLUMBING"
HDL_POWER"PVCCIO_CPU1";
"G\NAC"5;
%"VCC_CORE"
"1","(-2300,4600)","0","mstr_symbols","I161";
;
HDL_POWER"PVCCMCP_CPU1"
CDS_LIB"mstr_symbols"
VOLTAGE"+0.95";
"A"6;
%"VCC_CORE"
"1","(-5150,3700)","0","mstr_symbols","I162";
;
HDL_POWER"PVCCMCP_CPU1"
CDS_LIB"mstr_symbols";
"A"7;
%"VCC_CORE"
"1","(-1900,2675)","0","mstr_symbols","I164";
;
HDL_POWER"P1V8_MCP_CPU1"
CDS_LIB"mstr_symbols"
VOLTAGE"1.8";
"A"8;
%"VCC_CORE"
"1","(-1300,2675)","0","mstr_symbols","I165";
;
HDL_POWER"P1V8_MCP_CPU1"
CDS_LIB"mstr_symbols"
VOLTAGE"1.8";
"A"9;
%"VCC_CORE"
"1","(-1600,4175)","0","mstr_symbols","I166";
;
HDL_POWER"PVCCIOMCP_CPU1"
VOLTAGE"+0.95"
CDS_LIB"mstr_symbols";
"A"10;
%"VCC_CORE"
"1","(-1900,4125)","0","mstr_symbols","I167";
;
HDL_POWER"PVCCIOMCP_CPU1"
VOLTAGE"+0.95"
CDS_LIB"mstr_symbols";
"A"11;
%"VCC_CORE"
"1","(-1900,3325)","0","mstr_symbols","I168";
;
HDL_POWER"PVCCMCP_CPU1"
VOLTAGE"+0.95"
CDS_LIB"mstr_symbols";
"A"12;
%"RES"
"2","(-7950,775)","0","mstr_discrete","I169";
;
CDS_SEC"1"
CDS_LOCATION"R4C12"
PACK_TYPE"0402"
PART_NUMBER"G21796-078"
WATTAGE"1/16W"
GROUP"MCP"
MATERIAL"CHIP"
TOLERANCE"1%"
VALUE"8.06K"
LOCATION"R4C12"
ROOM"PVCCIN_CPU0_VR"
SEC"1"
CDS_LIB"mstr_discrete"
SEC_TYPE"0402";
"A"
$PN"1"28;
"B"
$PN"2"13;
%"RES"
"2","(-7600,750)","0","mstr_discrete","I170";
;
CDS_SEC"1"
CDS_LOCATION"R4C11"
PART_NUMBER"G21796-043"
GROUP"MCP"
LOCATION"R4C11"
VALUE"3.16K"
TOLERANCE"1%"
PACK_TYPE"0402"
MATERIAL"CHIP"
WATTAGE"1/16W"
SEC_TYPE"0402"
CDS_LIB"mstr_discrete"
SEC"1"
ROOM"PVCCIN_CPU0_VR";
"A"
$PN"1"29;
"B"
$PN"2"13;
%"GND"
"1","(-7950,450)","0","mstr_symbols","I171";
;
SIZE"1B"
CDS_LIB"mstr_symbols"
VOLTAGE"0.0V"
BODY_TYPE"PLUMBING"
HDL_POWER"GND";
"A\NAC"13;
%"P3V3"
"1","(-7325,4500)","0","mstr_symbols","I173";
;
CDS_LIB"mstr_symbols"
SIZE"1B"
VOLTAGE"+3.3V"
BODY_TYPE"PLUMBING"
HDL_POWER"P3V3";
"G\NAC"14;
%"CAPP"
"1","(-1300,3100)","0","mstr_discrete","I175";
;
CDS_SEC"1"
CDS_LOCATION"C4E29"
PACK_TYPE"3018"
VOLTAGE"2.5V"
TOLERANCE"20%"
VALUE"470UF"
LOCATION"C4E29"
MATERIAL"ALUM"
GROUP"PWR_MCP_CAP"
PART_NUMBER"699013-049"
CDS_LIB"mstr_discrete"
BOM_COST"PVMCP_MCP_CPU1_VR"
ROOM"PVMCP_MCP_CPU1_VR"
SEC_TYPE"3018"
SEC"1";
"B"
$PN"2"21;
"A"
$PN"1"12;
%"CAPP"
"1","(-1900,3950)","0","mstr_discrete","I29";
;
CDS_SEC"1"
TOLERANCE"20%"
VOLTAGE"2.5V"
MATERIAL"ALUM"
PACK_TYPE"3018"
PART_NUMBER"699013-049"
LOCATION"C4C1"
VALUE"470UF"
GROUP"PWR_MCP_CAP"
CDS_LIB"mstr_discrete"
SEC_TYPE"3018"
BOM_COST"PROC_VRD_VCCIN_CPU1"
SEC"1"
CDS_LOCATION"C4C1"
ROOM"P0V95_MCP_CPU1_DECAP_VR";
"B"
$PN"2"15;
"A"
$PN"1"11;
%"GND"
"1","(-1900,3775)","0","mstr_symbols","I30";
;
HDL_POWER"GND"
BODY_TYPE"PLUMBING"
VOLTAGE"0"
SIZE"1B"
CDS_LIB"mstr_symbols"
BOM_COST"PROC_VRD_VCCIN_CPU0"
ROOM"PVSA_CPU0_DECAP_VR";
"A\NAC"15;
%"CAP_A"
"1","(-1300,3950)","0","dev_discrete","I31";
;
LOCATION"C3C2"
VOLTAGE"6.3V"
TOLERANCE"10%"
MATERIAL"X6S"
PACK_TYPE"0402V"
PART_NUMBER"D97712-004"
VALUE"1.0UF"
GROUP"PWR_MCP_CAP"
CDS_LOCATION"C3C2"
CDS_LIB"dev_discrete"
CDS_SEC"1"
SEC_TYPE"0402V"
SEC"1"
ROOM"P0V95_FPGA_CPU1";
"B"
$PN"2"16;
"A"
$PN"1"10;
%"GND"
"1","(-1600,3675)","0","mstr_symbols","I37";
;
HDL_POWER"GND"
BODY_TYPE"PLUMBING"
VOLTAGE"0.0V"
CDS_LIB"mstr_symbols"
SIZE"1B";
"A\NAC"16;
%"CAP_A"
"1","(-1600,3950)","0","dev_discrete","I38";
;
VOLTAGE"6.3V"
MATERIAL"X6S"
PACK_TYPE"0402V"
LOCATION"C3C1"
TOLERANCE"10%"
VALUE"1.0UF"
PART_NUMBER"D97712-004"
GROUP"PWR_MCP_CAP"
CDS_LOCATION"C3C1"
CDS_LIB"dev_discrete"
CDS_SEC"1"
SEC_TYPE"0402V"
SEC"1"
ROOM"P0V95_FPGA_CPU1";
"B"
$PN"2"16;
"A"
$PN"1"10;
%"SCONN120_H61426002"
"1","(-3150,2800)","0","mstr_sconn","I45";
;
CDS_SEC"1"
MATERIAL"CONN"
LOCATION"J4E1"
GROUP"MCP"
PART_NUMBER"H61426-002"
ROOM"MCP VRM CPU1"
CDS_LOCATION"J4E1"
SEC"1"
SEC_TYPE"SM"
CDS_LIB"mstr_sconn"
PACK_TYPE"SM";
"IOB11"
$PN"B11"6;
"IOA1"
$PN"A1"2;
"IOB1"
$PN"B1"2;
"IOD1"
$PN"D1"42;
"IOC1"
$PN"C1"2;
"IOE1"
$PN"E1"3;
"IOF1"
$PN"F1"3;
"IOB2"
$PN"B2"2;
"IOA2"
$PN"A2"2;
"IOC2"
$PN"C2"2;
"IOD2"
$PN"D2"49;
"IOE2"
$PN"E2"3;
"IOF2"
$PN"F2"3;
"IOB3"
$PN"B3"2;
"IOA3"
$PN"A3"2;
"IOC3"
$PN"C3"2;
"IOD3"
$PN"D3"3;
"IOE3"
$PN"E3"3;
"IOF3"
$PN"F3"3;
"IOA4"
$PN"A4"48;
"IOB4"
$PN"B4"47;
"IOC4"
$PN"C4"7;
"IOD4"
$PN"D4"18;
"IOF4"
$PN"F4"18;
"IOE4"
$PN"E4"18;
"IOA5"
$PN"A5"7;
"IOB5"
$PN"B5"7;
"IOD5"
$PN"D5"18;
"IOC5"
$PN"C5"7;
"IOF5"
$PN"F5"50;
"IOE5"
$PN"E5"38;
"IOA6"
$PN"A6"7;
"IOB6"
$PN"B6"7;
"IOD6"
$PN"D6"18;
"IOC6"
$PN"C6"7;
"IOE6"
$PN"E6"18;
"IOF6"
$PN"F6"18;
"IOA7"
$PN"A7"7;
"IOC7"
$PN"C7"7;
"IOB7"
$PN"B7"7;
"IOE7"
$PN"E7"18;
"IOD7"
$PN"D7"18;
"IOF7"
$PN"F7"18;
"IOA8"
$PN"A8"7;
"IOB8"
$PN"B8"7;
"IOC8"
$PN"C8"7;
"IOD8"
$PN"D8"18;
"IOF8"
$PN"F8"18;
"IOE8"
$PN"E8"18;
"IOB9"
$PN"B9"7;
"IOA9"
$PN"A9"7;
"IOC9"
$PN"C9"7;
"IOD9"
$PN"D9"18;
"IOE9"
$PN"E9"18;
"IOF9"
$PN"F9"18;
"IOA10"
$PN"A10"7;
"IOB10"
$PN"B10"7;
"IOC10"
$PN"C10"7;
"IOE10"
$PN"E10"18;
"IOD10"
$PN"D10"18;
"IOF10"
$PN"F10"18;
"IOA11"
$PN"A11"6;
"IOC11"
$PN"C11"6;
"IOD11"
$PN"D11"17;
"IOE11"
$PN"E11"17;
"IOF11"
$PN"F11"17;
"IOA12"
$PN"A12"6;
"IOB12"
$PN"B12"6;
"IOD12"
$PN"D12"17;
"IOC12"
$PN"C12"6;
"IOF12"
$PN"F12"17;
"IOE12"
$PN"E12"17;
"IOA13"
$PN"A13"6;
"IOB13"
$PN"B13"6;
"IOC13"
$PN"C13"6;
"IOE13"
$PN"E13"17;
"IOD13"
$PN"D13"17;
"IOF13"
$PN"F13"17;
"IOA14"
$PN"A14"6;
"IOC14"
$PN"C14"6;
"IOB14"
$PN"B14"6;
"IOE14"
$PN"E14"17;
"IOD14"
$PN"D14"17;
"IOF14"
$PN"F14"17;
"IOA15"
$PN"A15"6;
"IOB15"
$PN"B15"6;
"IOC15"
$PN"C15"6;
"IOD15"
$PN"D15"17;
"IOF15"
$PN"F15"17;
"IOE15"
$PN"E15"17;
"IOA16"
$PN"A16"6;
"IOB16"
$PN"B16"6;
"IOC16"
$PN"C16"6;
"IOD16"
$PN"D16"17;
"IOE16"
$PN"E16"17;
"IOF16"
$PN"F16"17;
"IOA17"
$PN"A17"6;
"IOB17"
$PN"B17"6;
"IOC17"
$PN"C17"6;
"IOD17"
$PN"D17"17;
"IOE17"
$PN"E17"17;
"IOF17"
$PN"F17"17;
"IOA18"
$PN"A18"6;
"IOC18"
$PN"C18"6;
"IOB18"
$PN"B18"6;
"IOD18"
$PN"D18"17;
"IOE18"
$PN"E18"17;
"IOF18"
$PN"F18"17;
"IOA19"
$PN"A19"17;
"IOB19"
$PN"B19"17;
"IOD19"
$PN"D19"17;
"IOC19"
$PN"C19"17;
"IOF19"
$PN"F19"17;
"IOE19"
$PN"E19"17;
"IOB20"
$PN"B20"17;
"IOA20"
$PN"A20"17;
"IOD20"
$PN"D20"17;
"IOC20"
$PN"C20"17;
"IOE20"
$PN"E20"17;
"IOF20"
$PN"F20"17;
%"SCONN120_H61426002"
"1","(-6325,2725)","0","mstr_sconn","I46";
;
CDS_SEC"1"
PART_NUMBER"H61426-002"
GROUP"MCP"
MATERIAL"CONN"
LOCATION"J4B2"
ROOM"MCP VRM CPU1"
CDS_LOCATION"J4B2"
SEC"1"
SEC_TYPE"SM"
CDS_LIB"mstr_sconn"
PACK_TYPE"SM";
"IOB11"
$PN"B11"24;
"IOA1"
$PN"A1"23;
"IOB1"
$PN"B1"23;
"IOD1"
$PN"D1"14;
"IOC1"
$PN"C1"22;
"IOE1"
$PN"E1"1;
"IOF1"
$PN"F1"5;
"IOB2"
$PN"B2"23;
"IOA2"
$PN"A2"23;
"IOC2"
$PN"C2"22;
"IOD2"
$PN"D2"22;
"IOE2"
$PN"E2"22;
"IOF2"
$PN"F2"22;
"IOB3"
$PN"B3"23;
"IOA3"
$PN"A3"23;
"IOC3"
$PN"C3"22;
"IOD3"
$PN"D3"22;
"IOE3"
$PN"E3"22;
"IOF3"
$PN"F3"22;
"IOA4"
$PN"A4"23;
"IOB4"
$PN"B4"23;
"IOC4"
$PN"C4"22;
"IOD4"
$PN"D4"22;
"IOF4"
$PN"F4"22;
"IOE4"
$PN"E4"22;
"IOA5"
$PN"A5"23;
"IOB5"
$PN"B5"23;
"IOD5"
$PN"D5"22;
"IOC5"
$PN"C5"22;
"IOF5"
$PN"F5"22;
"IOE5"
$PN"E5"22;
"IOA6"
$PN"A6"23;
"IOB6"
$PN"B6"23;
"IOD6"
$PN"D6"22;
"IOC6"
$PN"C6"22;
"IOE6"
$PN"E6"22;
"IOF6"
$PN"F6"22;
"IOA7"
$PN"A7"23;
"IOC7"
$PN"C7"22;
"IOB7"
$PN"B7"23;
"IOE7"
$PN"E7"22;
"IOD7"
$PN"D7"22;
"IOF7"
$PN"F7"22;
"IOA8"
$PN"A8"23;
"IOB8"
$PN"B8"23;
"IOC8"
$PN"C8"27;
"IOD8"
$PN"D8"27;
"IOF8"
$PN"F8"36;
"IOE8"
$PN"E8"37;
"IOB9"
$PN"B9"27;
"IOA9"
$PN"A9"27;
"IOC9"
$PN"C9"27;
"IOD9"
$PN"D9"27;
"IOE9"
$PN"E9"27;
"IOF9"
$PN"F9"27;
"IOA10"
$PN"A10"27;
"IOB10"
$PN"B10"27;
"IOC10"
$PN"C10"27;
"IOE10"
$PN"E10"28;
"IOD10"
$PN"D10"27;
"IOF10"
$PN"F10"29;
"IOA11"
$PN"A11"24;
"IOC11"
$PN"C11"24;
"IOD11"
$PN"D11"26;
"IOE11"
$PN"E11"26;
"IOF11"
$PN"F11"26;
"IOA12"
$PN"A12"26;
"IOB12"
$PN"B12"26;
"IOD12"
$PN"D12"26;
"IOC12"
$PN"C12"26;
"IOF12"
$PN"F12"26;
"IOE12"
$PN"E12"26;
"IOA13"
$PN"A13"25;
"IOB13"
$PN"B13"25;
"IOC13"
$PN"C13"25;
"IOE13"
$PN"E13"26;
"IOD13"
$PN"D13"26;
"IOF13"
$PN"F13"26;
"IOA14"
$PN"A14"26;
"IOC14"
$PN"C14"26;
"IOB14"
$PN"B14"26;
"IOE14"
$PN"E14"26;
"IOD14"
$PN"D14"26;
"IOF14"
$PN"F14"26;
"IOA15"
$PN"A15"44;
"IOB15"
$PN"B15"51;
"IOC15"
$PN"C15"26;
"IOD15"
$PN"D15"26;
"IOF15"
$PN"F15"4;
"IOE15"
$PN"E15"4;
"IOA16"
$PN"A16"45;
"IOB16"
$PN"B16"46;
"IOC16"
$PN"C16"26;
"IOD16"
$PN"D16"26;
"IOE16"
$PN"E16"4;
"IOF16"
$PN"F16"4;
"IOA17"
$PN"A17"26;
"IOB17"
$PN"B17"26;
"IOC17"
$PN"C17"4;
"IOD17"
$PN"D17"4;
"IOE17"
$PN"E17"4;
"IOF17"
$PN"F17"4;
"IOA18"
$PN"A18"34;
"IOC18"
$PN"C18"4;
"IOB18"
$PN"B18"35;
"IOD18"
$PN"D18"4;
"IOE18"
$PN"E18"4;
"IOF18"
$PN"F18"4;
"IOA19"
$PN"A19"41;
"IOB19"
$PN"B19"43;
"IOD19"
$PN"D19"4;
"IOC19"
$PN"C19"4;
"IOF19"
$PN"F19"4;
"IOE19"
$PN"E19"4;
"IOB20"
$PN"B20"40;
"IOA20"
$PN"A20"33;
"IOD20"
$PN"D20"31;
"IOC20"
$PN"C20"39;
"IOE20"
$PN"E20"32;
"IOF20"
$PN"F20"30;
%"GND"
"1","(-2150,950)","0","mstr_symbols","I56";
;
SIZE"1B"
CDS_LIB"mstr_symbols"
VOLTAGE"0.0V"
BODY_TYPE"PLUMBING"
HDL_POWER"GND";
"A\NAC"17;
%"GND"
"1","(-3975,925)","0","mstr_symbols","I60";
;
CDS_LIB"mstr_symbols"
SIZE"1B"
VOLTAGE"0.0V"
BODY_TYPE"PLUMBING"
HDL_POWER"GND";
"A\NAC"18;
%"CAPP"
"1","(-1900,3100)","0","mstr_discrete","I61";
;
PART_NUMBER"699013-049"
VALUE"470UF"
PACK_TYPE"3018"
MATERIAL"ALUM"
VOLTAGE"2.5V"
TOLERANCE"20%"
LOCATION"C4E24"
GROUP"PWR_MCP_CAP"
CDS_LIB"mstr_discrete"
CDS_SEC"1"
CDS_LOCATION"C4E24"
$SEC"1"
BOM_COST"PVMCP_MCP_CPU1_VR"
ROOM"PVMCP_MCP_CPU1_VR";
"B"
$PN"2"21;
"A"
$PN"1"12;
%"CAPP"
"1","(-1600,3100)","0","mstr_discrete","I62";
;
CDS_SEC"1"
VOLTAGE"2.5V"
TOLERANCE"20%"
VALUE"470UF"
LOCATION"C6R16"
MATERIAL"ALUM"
PACK_TYPE"3018"
PART_NUMBER"699013-049"
GROUP"PWR_MCP_CAP"
ROOM"PVMCP_MCP_CPU1_VR"
CDS_LOCATION"C6R16"
SEC"1"
CDS_LIB"mstr_discrete"
BOM_COST"PVMCP_MCP_CPU1_VR"
SEC_TYPE"3018";
"B"
$PN"2"21;
"A"
$PN"1"12;
%"GND"
"1","(-1900,2175)","0","mstr_symbols","I64";
;
HDL_POWER"GND"
BODY_TYPE"PLUMBING"
VOLTAGE"0"
CDS_LIB"mstr_symbols"
SIZE"1B";
"A\NAC"19;
%"CAP_A"
"1","(-1000,2450)","0","dev_discrete","I68";
;
MATERIAL"X6S"
PART_NUMBER"D97712-004"
PACK_TYPE"0402V"
LOCATION"C4F1"
VALUE"1.0UF"
GROUP"PWR_MCP_CAP"
TOLERANCE"10%"
VOLTAGE"6.3V"
CDS_LOCATION"C4F1"
CDS_LIB"dev_discrete"
CDS_SEC"1"
SEC_TYPE"0402V"
SEC"1"
ROOM"P1V8_MCP_CPU1";
"B"
$PN"2"20;
"A"
$PN"1"9;
%"CAP_A"
"1","(-1300,2450)","0","dev_discrete","I70";
;
LOCATION"C4F3"
VOLTAGE"6.3V"
VALUE"1.0UF"
TOLERANCE"10%"
MATERIAL"X6S"
PACK_TYPE"0402V"
PART_NUMBER"D97712-004"
GROUP"PWR_MCP_CAP"
ROOM"P1V8_MCP_CPU1"
SEC"1"
SEC_TYPE"0402V"
CDS_SEC"1"
CDS_LIB"dev_discrete"
CDS_LOCATION"C4F3";
"B"
$PN"2"20;
"A"
$PN"1"9;
%"GND"
"1","(-1300,2175)","0","mstr_symbols","I75";
;
HDL_POWER"GND"
BODY_TYPE"PLUMBING"
CDS_LIB"mstr_symbols"
SIZE"1B"
VOLTAGE"0.0V";
"A\NAC"20;
%"GND"
"1","(-1900,2825)","0","mstr_symbols","I81";
;
ROOM"PVSA_CPU0_DECAP_VR"
CDS_LIB"mstr_symbols"
SIZE"1B"
BOM_COST"PROC_VRD_VCCIN_CPU0"
VOLTAGE"0"
BODY_TYPE"PLUMBING"
HDL_POWER"GND";
"A\NAC"21;
%"GND"
"1","(-7150,1875)","0","mstr_symbols","I85";
;
SIZE"1B"
CDS_LIB"mstr_symbols"
VOLTAGE"0.0V"
BODY_TYPE"PLUMBING"
HDL_POWER"GND";
"A\NAC"22;
%"P12V_STBY"
"1","(-6950,4750)","0","mstr_symbols","I86";
;
SIZE"1B"
CDS_LIB"mstr_symbols"
VOLTAGE"12.0V"
BODY_TYPE"PLUMBING"
HDL_POWER"P12V_STBY";
"G\NAC"23;
%"P3V3_STBY"
"1","(-5525,4525)","0","mstr_symbols","I87";
;
SIZE"1B"
CDS_LIB"mstr_symbols"
VOLTAGE"+3.3V"
BODY_TYPE"PLUMBING"
HDL_POWER"P3V3_STBY";
"G\NAC"24;
%"P5V_STBY"
"1","(-5500,3850)","0","mstr_symbols","I88";
;
SIZE"1B"
CDS_LIB"mstr_symbols"
VOLTAGE"+5.0V"
BODY_TYPE"PLUMBING"
HDL_POWER"P5V_STBY";
"G\NAC"25;
%"GND"
"1","(-5125,2175)","0","mstr_symbols","I94";
;
SIZE"1B"
CDS_LIB"mstr_symbols"
VOLTAGE"0.0V"
BODY_TYPE"PLUMBING"
HDL_POWER"GND";
"A\NAC"26;
%"GND"
"1","(-7125,1425)","0","mstr_symbols","I95";
;
SIZE"1B"
CDS_LIB"mstr_symbols"
VOLTAGE"0.0V"
BODY_TYPE"PLUMBING"
HDL_POWER"GND";
"A\NAC"27;
END.
